(kicad_pcb
	(version 20260206)
	(generator "pcbnew")
	(generator_version "10.0")
	(general
		(thickness 1.6)
		(legacy_teardrops no)
	)
	(paper "A4")
	(title_block
		(title "03242023_DA0F0TMBIJ0_F0T_Motherboard_J_brd_V01_OCP.brd")
		(comment 1 "Grand Teton / footprints 3716-3716 of 6105")
	)
	(layers
		(0 "F.Cu" signal "TOP")
		(4 "In1.Cu" signal "GND")
		(6 "In2.Cu" signal "IN1")
		(8 "In3.Cu" signal "GND1")
		(10 "In4.Cu" signal "IN2")
		(12 "In5.Cu" signal "GND2")
		(14 "In6.Cu" signal "IN3")
		(16 "In7.Cu" signal "GND3")
		(18 "In8.Cu" signal "VCC")
		(20 "In9.Cu" signal "VCC1")
		(22 "In10.Cu" signal "GND4")
		(24 "In11.Cu" signal "IN4")
		(26 "In12.Cu" signal "GND5")
		(28 "In13.Cu" signal "IN5")
		(30 "In14.Cu" signal "GND6")
		(32 "In15.Cu" signal "IN6")
		(34 "In16.Cu" signal "GND7")
		(2 "B.Cu" signal "BOTTOM")
		(9 "F.Adhes" user "F.Adhesive")
		(11 "B.Adhes" user "B.Adhesive")
		(13 "F.Paste" user "Package Geometry/Pastemask Top")
		(15 "B.Paste" user "Package Geometry/Pastemask Bottom")
		(5 "F.SilkS" user "Ref Des/Silkscreen Top")
		(7 "B.SilkS" user "Ref Des/Silkscreen Bottom")
		(1 "F.Mask" user "Board Geometry/Soldermask Top")
		(3 "B.Mask" user "Board Geometry/Soldermask Bottom")
		(17 "Dwgs.User" user "User.Drawings")
		(19 "Cmts.User" user "User.Comments")
		(21 "Eco1.User" user "User.Eco1")
		(23 "Eco2.User" user "User.Eco2")
		(25 "Edge.Cuts" user "Board Geometry/Outline")
		(27 "Margin" user)
		(31 "F.CrtYd" user "Package Geometry/Place Bound Top")
		(29 "B.CrtYd" user "Package Geometry/Place Bound Bottom")
		(35 "F.Fab" user "Ref Des/Assembly Top")
		(33 "B.Fab" user "Ref Des/Assembly Bottom")
	)
	(footprint ""
		(layer "F.Cu")
		(at 394.899896 -56.999886)
		(property "Reference" "J42"
			(at 4.46278 8.605012 0)
			(unlocked yes)
			(layer "F.SilkS")
			(effects
				(font
					(size 0.7874 0.5842)
					(thickness 0.1524)
				)
				(justify left)
			)
		)
		(property "Value" ""
			(at 0 0 0)
			(layer "F.Fab")
			(effects
				(font
					(size 1.27 1.27)
				)
			)
		)
		(duplicate_pad_numbers_are_jumpers no)
		(fp_line
			(start -3.620008 -10.655046)
			(end 2.032 -10.655046)
			(stroke
				(width 0.1524)
				(type default)
			)
			(layer "F.SilkS")
		)
		(fp_line
			(start -3.620008 -7.5184)
			(end -3.620008 -10.655046)
			(stroke
				(width 0.1524)
				(type default)
			)
			(layer "F.SilkS")
		)
		(fp_line
			(start -3.620008 10.655046)
			(end -3.620008 7.5184)
			(stroke
				(width 0.1524)
				(type default)
			)
			(layer "F.SilkS")
		)
		(fp_line
			(start 2.032 10.655046)
			(end -3.620008 10.655046)
			(stroke
				(width 0.1524)
				(type default)
			)
			(layer "F.SilkS")
		)
		(fp_line
			(start 3.302 -10.655046)
			(end 3.620008 -10.655046)
			(stroke
				(width 0.1524)
				(type default)
			)
			(layer "F.SilkS")
		)
		(fp_line
			(start 3.620008 -10.655046)
			(end 3.620008 -7.5184)
			(stroke
				(width 0.1524)
				(type default)
			)
			(layer "F.SilkS")
		)
		(fp_line
			(start 3.620008 7.5184)
			(end 3.620008 10.655046)
			(stroke
				(width 0.1524)
				(type default)
			)
			(layer "F.SilkS")
		)
		(fp_line
			(start 3.620008 10.655046)
			(end 3.302 10.655046)
			(stroke
				(width 0.1524)
				(type default)
			)
			(layer "F.SilkS")
		)
		(fp_poly
			(pts
				(xy -4.1656 -7.249922) (xy -5.08 -6.805422) (xy -5.08 -7.669022)
			)
			(stroke
				(width 0)
				(type default)
			)
			(fill yes)
			(layer "F.SilkS")
		)
		(fp_line
			(start -3.620008 -10.655046)
			(end 3.620008 -10.655046)
			(stroke
				(width 0.1)
				(type default)
			)
			(layer "F.Fab")
		)
		(fp_line
			(start -3.620008 10.655046)
			(end -3.620008 -10.655046)
			(stroke
				(width 0.1)
				(type default)
			)
			(layer "F.Fab")
		)
		(fp_line
			(start 3.620008 -10.655046)
			(end 3.620008 10.655046)
			(stroke
				(width 0.1)
				(type default)
			)
			(layer "F.Fab")
		)
		(fp_line
			(start 3.620008 10.655046)
			(end -3.620008 10.655046)
			(stroke
				(width 0.1)
				(type default)
			)
			(layer "F.Fab")
		)
		(fp_poly
			(pts
				(xy -4.1656 -7.249922) (xy -5.08 -7.669022) (xy -5.08 -6.805422)
			)
			(stroke
				(width 0)
				(type default)
			)
			(fill yes)
			(layer "F.Fab")
		)
		(fp_text user "59"
			(at -5.816092 8.908034 0)
			(unlocked yes)
			(layer "F.SilkS")
			(effects
				(font
					(size 0.7874 0.5842)
					(thickness 0.1524)
				)
				(justify left)
			)
		)
		(fp_text user "60"
			(at 4.475988 6.535674 0)
			(unlocked yes)
			(layer "F.SilkS")
			(effects
				(font
					(size 0.7874 0.5842)
					(thickness 0.1524)
				)
				(justify left)
			)
		)
		(fp_text user "2"
			(at 4.504944 -7.675626 0)
			(unlocked yes)
			(layer "F.SilkS")
			(effects
				(font
					(size 0.7874 0.5842)
					(thickness 0.1524)
				)
				(justify left)
			)
		)
		(fp_text user "59"
			(at -4.683252 6.589522 270)
			(unlocked yes)
			(layer "F.Fab")
			(effects
				(font
					(size 0.7874 0.5842)
					(thickness 0.1524)
				)
				(justify left)
			)
		)
		(fp_text user "2"
			(at 4.613148 -7.592822 270)
			(unlocked yes)
			(layer "F.Fab")
			(effects
				(font
					(size 0.7874 0.5842)
					(thickness 0.1524)
				)
				(justify left)
			)
		)
		(fp_text user "60"
			(at 4.613148 6.513322 270)
			(unlocked yes)
			(layer "F.Fab")
			(effects
				(font
					(size 0.7874 0.5842)
					(thickness 0.1524)
				)
				(justify left)
			)
		)
		(pad "" np_thru_hole circle
			(at 2.670048 -10.065004 270)
			(size 1.0414 1.0414)
			(drill 1.0414)
			(layers "*.Cu" "*.Mask")
			(clearance 0.381)
			(thermal_gap 0.381)
		)
		(pad "" np_thru_hole circle
			(at 2.670048 10.065004 270)
			(size 1.0414 1.0414)
			(drill 1.0414)
			(layers "*.Cu" "*.Mask")
			(clearance 0.381)
			(thermal_gap 0.381)
		)
		(pad "1" smd rect
			(at -2.86512 -7.249922 270)
			(size 0.2794 2.286)
			(layers "F.Cu" "F.Mask" "F.Paste")
			(net "P1V05_PCH_AUX")
		)
		(pad "2" smd rect
			(at 2.86512 -7.249922 270)
			(size 0.2794 2.286)
			(layers "F.Cu" "F.Mask" "F.Paste")
			(net "JTAG_DBP_TMS_R")
		)
		(pad "3" smd rect
			(at -2.86512 -6.75005 270)
			(size 0.2794 2.286)
			(layers "F.Cu" "F.Mask" "F.Paste")
			(net "JTAG_DBP_CPU_GTL_TCK_R")
		)
		(pad "4" smd rect
			(at 2.86512 -6.75005 270)
			(size 0.2794 2.286)
			(layers "F.Cu" "F.Mask" "F.Paste")
			(net "JTAG_DBP_TDO_R")
		)
		(pad "5" smd rect
			(at -2.86512 -6.249924 270)
			(size 0.2794 2.286)
			(layers "F.Cu" "F.Mask" "F.Paste")
			(net "JTAG_DBP_TDI_R")
		)
		(pad "6" smd rect
			(at 2.86512 -6.249924 270)
			(size 0.2794 2.286)
			(layers "F.Cu" "F.Mask" "F.Paste")
			(net "JTAG_RST_DBP_RST_CO_N")
		)
		(pad "7" smd rect
			(at -2.86512 -5.750052 270)
			(size 0.2794 2.286)
			(layers "F.Cu" "F.Mask" "F.Paste")
			(net "JTAG_DBP_PMODE")
		)
		(pad "8" smd rect
			(at 2.86512 -5.750052 270)
			(size 0.2794 2.286)
			(layers "F.Cu" "F.Mask" "F.Paste")
			(net "PD_TRST_P3")
		)
		(pad "9" smd rect
			(at -2.86512 -5.249926 270)
			(size 0.2794 2.286)
			(layers "F.Cu" "F.Mask" "F.Paste")
			(net "NC_MIPI60_P9")
		)
		(pad "10" smd rect
			(at 2.86512 -5.249926 270)
			(size 0.2794 2.286)
			(layers "F.Cu" "F.Mask" "F.Paste")
			(net "JTAG_DBP_PREQ_N_R")
		)
		(pad "11" smd rect
			(at -2.86512 -4.750054 270)
			(size 0.2794 2.286)
			(layers "F.Cu" "F.Mask" "F.Paste")
			(net "JTAG_DBP_PRDY_R1_N")
		)
		(pad "12" smd rect
			(at 2.86512 -4.750054 270)
			(size 0.2794 2.286)
			(layers "F.Cu" "F.Mask" "F.Paste")
			(net "P1V8_PCH_AUX")
		)
		(pad "13" smd rect
			(at -2.86512 -4.249928 270)
			(size 0.2794 2.286)
			(layers "F.Cu" "F.Mask" "F.Paste")
			(net "JTAG_TRC_PCH_PTI0_CLK")
		)
		(pad "14" smd rect
			(at 2.86512 -4.249928 270)
			(size 0.2794 2.286)
			(layers "F.Cu" "F.Mask" "F.Paste")
			(net "GND")
		)
		(pad "15" smd rect
			(at -2.86512 -3.750056 270)
			(size 0.2794 2.286)
			(layers "F.Cu" "F.Mask" "F.Paste")
			(net "JTAG_DBP_PCH_DEBUG_CONSENT_N")
		)
		(pad "16" smd rect
			(at 2.86512 -3.750056 270)
			(size 0.2794 2.286)
			(layers "F.Cu" "F.Mask" "F.Paste")
			(net "GND")
		)
		(pad "17" smd rect
			(at -2.86512 -3.24993 270)
			(size 0.2794 2.286)
			(layers "F.Cu" "F.Mask" "F.Paste")
			(net "JTAG_DBP_PRESENT_R_N")
		)
		(pad "18" smd rect
			(at 2.86512 -3.24993 270)
			(size 0.2794 2.286)
			(layers "F.Cu" "F.Mask" "F.Paste")
			(net "NC_DBP_P18")
		)
		(pad "19" smd rect
			(at -2.86512 -2.750058 270)
			(size 0.2794 2.286)
			(layers "F.Cu" "F.Mask" "F.Paste")
			(net "JTAG_TRC_PCH_PTI<0>")
		)
		(pad "20" smd rect
			(at 2.86512 -2.750058 270)
			(size 0.2794 2.286)
			(layers "F.Cu" "F.Mask" "F.Paste")
			(net "NC_DBP_P20")
		)
		(pad "21" smd rect
			(at -2.86512 -2.249932 270)
			(size 0.2794 2.286)
			(layers "F.Cu" "F.Mask" "F.Paste")
			(net "JTAG_TRC_PCH_PTI<1>")
		)
		(pad "22" smd rect
			(at 2.86512 -2.249932 270)
			(size 0.2794 2.286)
			(layers "F.Cu" "F.Mask" "F.Paste")
			(net "NC_DBP_P22")
		)
		(pad "23" smd rect
			(at -2.86512 -1.75006 270)
			(size 0.2794 2.286)
			(layers "F.Cu" "F.Mask" "F.Paste")
			(net "JTAG_TRC_PCH_PTI<2>")
		)
		(pad "24" smd rect
			(at 2.86512 -1.75006 270)
			(size 0.2794 2.286)
			(layers "F.Cu" "F.Mask" "F.Paste")
			(net "NC_DBP_P24")
		)
		(pad "25" smd rect
			(at -2.86512 -1.249934 270)
			(size 0.2794 2.286)
			(layers "F.Cu" "F.Mask" "F.Paste")
			(net "JTAG_TRC_PCH_PTI<3>")
		)
		(pad "26" smd rect
			(at 2.86512 -1.249934 270)
			(size 0.2794 2.286)
			(layers "F.Cu" "F.Mask" "F.Paste")
			(net "NC_DBP_P26")
		)
		(pad "27" smd rect
			(at -2.86512 -0.750062 270)
			(size 0.2794 2.286)
			(layers "F.Cu" "F.Mask" "F.Paste")
			(net "JTAG_TRC_PCH_PTI<4>")
		)
		(pad "28" smd rect
			(at 2.86512 -0.750062 270)
			(size 0.2794 2.286)
			(layers "F.Cu" "F.Mask" "F.Paste")
			(net "NC_DBP_P28")
		)
		(pad "29" smd rect
			(at -2.86512 -0.249936 270)
			(size 0.2794 2.286)
			(layers "F.Cu" "F.Mask" "F.Paste")
			(net "JTAG_TRC_PCH_PTI<5>")
		)
		(pad "30" smd rect
			(at 2.86512 -0.249936 270)
			(size 0.2794 2.286)
			(layers "F.Cu" "F.Mask" "F.Paste")
			(net "NC_DBP_P30")
		)
		(pad "31" smd rect
			(at -2.86512 0.249936 270)
			(size 0.2794 2.286)
			(layers "F.Cu" "F.Mask" "F.Paste")
			(net "JTAG_TRC_PCH_PTI<6>")
		)
		(pad "32" smd rect
			(at 2.86512 0.249936 270)
			(size 0.2794 2.286)
			(layers "F.Cu" "F.Mask" "F.Paste")
			(net "NC_DBP_P32")
		)
		(pad "33" smd rect
			(at -2.86512 0.750062 270)
			(size 0.2794 2.286)
			(layers "F.Cu" "F.Mask" "F.Paste")
			(net "JTAG_TRC_PCH_PTI<7>")
		)
		(pad "34" smd rect
			(at 2.86512 0.750062 270)
			(size 0.2794 2.286)
			(layers "F.Cu" "F.Mask" "F.Paste")
			(net "NC_DBP_P34")
		)
		(pad "35" smd rect
			(at -2.86512 1.249934 270)
			(size 0.2794 2.286)
			(layers "F.Cu" "F.Mask" "F.Paste")
			(net "JTAG_TRC_PCH_PTI<8>")
		)
		(pad "36" smd rect
			(at 2.86512 1.249934 270)
			(size 0.2794 2.286)
			(layers "F.Cu" "F.Mask" "F.Paste")
			(net "JTAG_DBP_BOOT_HALT_N")
		)
		(pad "37" smd rect
			(at -2.86512 1.75006 270)
			(size 0.2794 2.286)
			(layers "F.Cu" "F.Mask" "F.Paste")
			(net "JTAG_TRC_PCH_PTI<9>")
		)
		(pad "38" smd rect
			(at 2.86512 1.75006 270)
			(size 0.2794 2.286)
			(layers "F.Cu" "F.Mask" "F.Paste")
			(net "FM_CPU_FBRK_DEBUG_N")
		)
		(pad "39" smd rect
			(at -2.86512 2.249932 270)
			(size 0.2794 2.286)
			(layers "F.Cu" "F.Mask" "F.Paste")
			(net "JTAG_TRC_PCH_PTI<10>")
		)
		(pad "40" smd rect
			(at 2.86512 2.249932 270)
			(size 0.2794 2.286)
			(layers "F.Cu" "F.Mask" "F.Paste")
			(net "JTAG_DBP_POWER_BTN_N")
		)
		(pad "41" smd rect
			(at -2.86512 2.750058 270)
			(size 0.2794 2.286)
			(layers "F.Cu" "F.Mask" "F.Paste")
			(net "JTAG_TRC_PCH_PTI<11>")
		)
		(pad "42" smd rect
			(at 2.86512 2.750058 270)
			(size 0.2794 2.286)
			(layers "F.Cu" "F.Mask" "F.Paste")
			(net "JTAG_RST_DBP_RSMRST_N")
		)
		(pad "43" smd rect
			(at -2.86512 3.24993 270)
			(size 0.2794 2.286)
			(layers "F.Cu" "F.Mask" "F.Paste")
			(net "JTAG_TRC_PCH_PTI<12>")
		)
		(pad "44" smd rect
			(at 2.86512 3.24993 270)
			(size 0.2794 2.286)
			(layers "F.Cu" "F.Mask" "F.Paste")
			(net "NC_DBP_P44")
		)
		(pad "45" smd rect
			(at -2.86512 3.750056 270)
			(size 0.2794 2.286)
			(layers "F.Cu" "F.Mask" "F.Paste")
			(net "JTAG_TRC_PCH_PTI<13>")
		)
		(pad "46" smd rect
			(at 2.86512 3.750056 270)
			(size 0.2794 2.286)
			(layers "F.Cu" "F.Mask" "F.Paste")
			(net "NC_DBP_P46")
		)
		(pad "47" smd rect
			(at -2.86512 4.249928 270)
			(size 0.2794 2.286)
			(layers "F.Cu" "F.Mask" "F.Paste")
			(net "JTAG_TRC_PCH_PTI<14>")
		)
		(pad "48" smd rect
			(at 2.86512 4.249928 270)
			(size 0.2794 2.286)
			(layers "F.Cu" "F.Mask" "F.Paste")
			(net "SMB_HOST_3V3AUX_XDP_R_SCL")
		)
		(pad "49" smd rect
			(at -2.86512 4.750054 270)
			(size 0.2794 2.286)
			(layers "F.Cu" "F.Mask" "F.Paste")
			(net "JTAG_TRC_PCH_PTI<15>")
		)
		(pad "50" smd rect
			(at 2.86512 4.750054 270)
			(size 0.2794 2.286)
			(layers "F.Cu" "F.Mask" "F.Paste")
			(net "SMB_HOST_3V3AUX_XDP_R_SDA")
		)
		(pad "51" smd rect
			(at -2.86512 5.249926 270)
			(size 0.2794 2.286)
			(layers "F.Cu" "F.Mask" "F.Paste")
			(net "JTAG_DBP_TCK_R_TCK")
		)
		(pad "52" smd rect
			(at 2.86512 5.249926 270)
			(size 0.2794 2.286)
			(layers "F.Cu" "F.Mask" "F.Paste")
			(net "P3V3_AUX")
		)
		(pad "53" smd rect
			(at -2.86512 5.750052 270)
			(size 0.2794 2.286)
			(layers "F.Cu" "F.Mask" "F.Paste")
			(net "JTAG_DBP_CPU_HOOK9_MBP3_GTL_N")
		)
		(pad "54" smd rect
			(at 2.86512 5.750052 270)
			(size 0.2794 2.286)
			(layers "F.Cu" "F.Mask" "F.Paste")
			(net "NC_DBP_P54")
		)
		(pad "55" smd rect
			(at -2.86512 6.249924 270)
			(size 0.2794 2.286)
			(layers "F.Cu" "F.Mask" "F.Paste")
			(net "JTAG_DBP_CPU_HOOK8_MBP2_GTL_N")
		)
		(pad "56" smd rect
			(at 2.86512 6.249924 270)
			(size 0.2794 2.286)
			(layers "F.Cu" "F.Mask" "F.Paste")
			(net "NC_DBP_P56")
		)
		(pad "57" smd rect
			(at -2.86512 6.75005 270)
			(size 0.2794 2.286)
			(layers "F.Cu" "F.Mask" "F.Paste")
			(net "GND")
		)
		(pad "58" smd rect
			(at 2.86512 6.75005 270)
			(size 0.2794 2.286)
			(layers "F.Cu" "F.Mask" "F.Paste")
			(net "GND")
		)
		(pad "59" smd rect
			(at -2.86512 7.249922 270)
			(size 0.2794 2.286)
			(layers "F.Cu" "F.Mask" "F.Paste")
			(net "JTAG_TRC_PCH_PTI1_CLK")
		)
		(pad "60" smd rect
			(at 2.86512 7.249922 270)
			(size 0.2794 2.286)
			(layers "F.Cu" "F.Mask" "F.Paste")
			(net "GND")
		)
		(pad "G1" smd rect
			(at 0 -8.065008)
			(size 0.4318 2.54)
			(layers "F.Cu" "F.Mask" "F.Paste")
			(net "GND")
		)
		(pad "G2" smd rect
			(at 0 -3.175)
			(size 0.4318 4.699)
			(layers "F.Cu" "F.Mask" "F.Paste")
			(net "GND")
		)
		(pad "G3" smd rect
			(at 0 3.175)
			(size 0.4318 4.699)
			(layers "F.Cu" "F.Mask" "F.Paste")
			(net "GND")
		)
		(pad "G4" smd rect
			(at 0 8.065008)
			(size 0.4318 2.54)
			(layers "F.Cu" "F.Mask" "F.Paste")
			(net "GND")
		)
		(zone
			(layers "F.Cu" "B.Cu" "In1.Cu" "In2.Cu" "In3.Cu" "In4.Cu" "In5.Cu" "In6.Cu"
				"In7.Cu" "In8.Cu" "In9.Cu" "In10.Cu" "In11.Cu" "In12.Cu" "In13.Cu" "In14.Cu"
				"In15.Cu" "In16.Cu"
			)
			(hatch none 0.5)
			(connect_pads
				(clearance 0)
			)
			(min_thickness 0.25)
			(keepout
				(tracks not_allowed)
				(vias allowed)
				(pads allowed)
				(copperpour not_allowed)
				(footprints allowed)
			)
			(placement
				(enabled no)
				(sheetname "")
			)
			(fill
				(thermal_gap 0.5)
				(thermal_bridge_width 0.5)
				(island_removal_mode 0)
			)
			(polygon
				(pts
					(arc
						(start 398.497044 -67.06489)
						(mid 396.642844 -67.06489)
						(end 398.497044 -67.06489)
					)
				)
			)
		)
		(zone
			(layers "F.Cu" "B.Cu" "In1.Cu" "In2.Cu" "In3.Cu" "In4.Cu" "In5.Cu" "In6.Cu"
				"In7.Cu" "In8.Cu" "In9.Cu" "In10.Cu" "In11.Cu" "In12.Cu" "In13.Cu" "In14.Cu"
				"In15.Cu" "In16.Cu"
			)
			(hatch none 0.5)
			(connect_pads
				(clearance 0)
			)
			(min_thickness 0.25)
			(keepout
				(tracks not_allowed)
				(vias allowed)
				(pads allowed)
				(copperpour not_allowed)
				(footprints allowed)
			)
			(placement
				(enabled no)
				(sheetname "")
			)
			(fill
				(thermal_gap 0.5)
				(thermal_bridge_width 0.5)
				(island_removal_mode 0)
			)
			(polygon
				(pts
					(arc
						(start 398.497044 -46.934882)
						(mid 396.642844 -46.934882)
						(end 398.497044 -46.934882)
					)
				)
			)
		)
	)
)
